# T6G (Grand Teton) — schematic netlist excerpt (pin names and nets, part order shuffled) for the footprints in the layout excerpt that follows; sources: Cadence DE-HDL packaged netlist, KiCad conversion of 04192023_DAF0TMB3IC0_F0TG_MB_C_brd_V02_OCP.brd

J110  CONN112_10137002101LF  CONN112_10137002-101LF IO  pkg HSD_F112D8_P2W1-2_RDH  page 120
  A1  = GPU_FPGA_EROT_RECOV_BUF_N
  A2  = GND
  A3  = GPU_HMC_PRSNT_N
  A4  = GND
  A5  = GPU_BASE_HMC_READY
  A6  = GND
  A7  = GPU_BASE_STBY_EN_BUF
  A8  = GND
  B1  = GND
  B2  = P5E_CPU1_P2_RX_BUF_DN<1>
  B3  = GND
  B4  = P5E_CPU1_P2_RX_BUF_DN<3>
  B5  = GND
  B6  = P5E_CPU1_P2_RX_BUF_DN<5>
  B7  = GND
  B8  = P5E_CPU1_P2_RX_BUF_DN<7>
  C1  = P5E_CPU1_P2_RX_BUF_DN<0>
  C2  = P5E_CPU1_P2_RX_BUF_DP<1>
  C3  = P5E_CPU1_P2_RX_BUF_DN<2>
  C4  = P5E_CPU1_P2_RX_BUF_DP<3>
  C5  = P5E_CPU1_P2_RX_BUF_DN<4>
  C6  = P5E_CPU1_P2_RX_BUF_DP<5>
  C7  = P5E_CPU1_P2_RX_BUF_DN<6>
  C8  = P5E_CPU1_P2_RX_BUF_DP<7>
  D1  = P5E_CPU1_P2_RX_BUF_DP<0>
  D2  = GND
  D3  = P5E_CPU1_P2_RX_BUF_DP<2>
  D4  = GND
  D5  = P5E_CPU1_P2_RX_BUF_DP<4>
  D6  = GND
  D7  = P5E_CPU1_P2_RX_BUF_DP<6>
  D8  = GND
  E1  = GND
  E2  = P5E_CPU1_P3_RX_BUF_DN<1>
  E3  = GND
  E4  = P5E_CPU1_P3_RX_BUF_DN<3>
  E5  = GND
  E6  = P5E_CPU1_P3_RX_BUF_DN<5>
  E7  = GND
  E8  = P5E_CPU1_P3_RX_BUF_DN<7>
  F1  = P5E_CPU1_P3_RX_BUF_DN<0>
  F2  = P5E_CPU1_P3_RX_BUF_DP<1>
  F3  = P5E_CPU1_P3_RX_BUF_DN<2>
  F4  = P5E_CPU1_P3_RX_BUF_DP<3>
  F5  = P5E_CPU1_P3_RX_BUF_DN<4>
  F6  = P5E_CPU1_P3_RX_BUF_DP<5>
  F7  = P5E_CPU1_P3_RX_BUF_DN<6>
  F8  = P5E_CPU1_P3_RX_BUF_DP<7>
  G1  = P5E_CPU1_P3_RX_BUF_DP<0>
  G2  = GND
  G3  = P5E_CPU1_P3_RX_BUF_DP<2>
  G4  = GND
  G5  = P5E_CPU1_P3_RX_BUF_DP<4>
  G6  = GND
  G7  = P5E_CPU1_P3_RX_BUF_DP<6>
  G8  = GND
  H1  = GND
  H2  = P5E_CPU1_P2_TX_BUF_C_DN<1>
  H3  = GND
  H4  = P5E_CPU1_P2_TX_BUF_C_DN<3>
  H5  = GND
  H6  = P5E_CPU1_P2_TX_BUF_C_DN<5>
  H7  = GND
  H8  = P5E_CPU1_P2_TX_BUF_C_DN<7>
  I1  = P5E_CPU1_P2_TX_BUF_C_DN<0>
  I2  = P5E_CPU1_P2_TX_BUF_C_DP<1>
  I3  = P5E_CPU1_P2_TX_BUF_C_DN<2>
  I4  = P5E_CPU1_P2_TX_BUF_C_DP<3>
  I5  = P5E_CPU1_P2_TX_BUF_C_DN<4>
  I6  = P5E_CPU1_P2_TX_BUF_C_DP<5>
  I7  = P5E_CPU1_P2_TX_BUF_C_DN<6>
  I8  = P5E_CPU1_P2_TX_BUF_C_DP<7>
  J1  = P5E_CPU1_P2_TX_BUF_C_DP<0>
  J2  = GND
  J3  = P5E_CPU1_P2_TX_BUF_C_DP<2>
  J4  = GND
  J5  = P5E_CPU1_P2_TX_BUF_C_DP<4>
  J6  = GND
  J7  = P5E_CPU1_P2_TX_BUF_C_DP<6>
  J8  = GND
  K1  = GND
  K2  = P5E_CPU1_P3_TX_BUF_C_DN<1>
  K3  = GND
  K4  = P5E_CPU1_P3_TX_BUF_C_DN<3>
  K5  = GND
  K6  = P5E_CPU1_P3_TX_BUF_C_DN<5>
  K7  = GND
  K8  = P5E_CPU1_P3_TX_BUF_C_DN<7>
  L1  = P5E_CPU1_P3_TX_BUF_C_DN<0>
  L2  = P5E_CPU1_P3_TX_BUF_C_DP<1>
  L3  = P5E_CPU1_P3_TX_BUF_C_DN<2>
  L4  = P5E_CPU1_P3_TX_BUF_C_DP<3>
  L5  = P5E_CPU1_P3_TX_BUF_C_DN<4>
  L6  = P5E_CPU1_P3_TX_BUF_C_DP<5>
  L7  = P5E_CPU1_P3_TX_BUF_C_DN<6>
  L8  = P5E_CPU1_P3_TX_BUF_C_DP<7>
  M1  = P5E_CPU1_P3_TX_BUF_C_DP<0>
  M2  = GND
  M3  = P5E_CPU1_P3_TX_BUF_C_DP<2>
  M4  = GND
  M5  = P5E_CPU1_P3_TX_BUF_C_DP<4>
  M6  = GND
  M7  = P5E_CPU1_P3_TX_BUF_C_DP<6>
  M8  = GND
  N1  = GND
  N2  = GPU_FPGA_BOOT_EN_BUF
  N3  = GND
  N4  = FM_SMB_1_ALERT_GPU_N
  N5  = GND
  N6  = FM_SMB_2_ALERT_GPU_N
  N7  = GND
  N8  = GPU_FPGA_EROT_RST_BUF_N

(kicad_pcb
	(version 20260206)
	(generator "pcbnew")
	(generator_version "10.0")
	(general
		(thickness 1.6)
		(legacy_teardrops no)
	)
	(paper "A4")
	(title_block
		(title "04192023_DAF0TMB3IC0_F0TG_MB_C_brd_V02_OCP.brd")
		(comment 1 "Grand Teton / footprint 3846 of 8354 (J110), pads 1-31 of 48")
	)
	(layers
		(0 "F.Cu" signal "TOP")
		(4 "In1.Cu" signal "GND")
		(6 "In2.Cu" signal "IN1")
		(8 "In3.Cu" signal "GND1")
		(10 "In4.Cu" signal "IN2")
		(12 "In5.Cu" signal "GND2")
		(14 "In6.Cu" signal "IN3")
		(16 "In7.Cu" signal "GND3")
		(18 "In8.Cu" signal "VCC")
		(20 "In9.Cu" signal "VCC1")
		(22 "In10.Cu" signal "GND4")
		(24 "In11.Cu" signal "IN4")
		(26 "In12.Cu" signal "GND5")
		(28 "In13.Cu" signal "IN5")
		(30 "In14.Cu" signal "GND6")
		(32 "In15.Cu" signal "IN6")
		(34 "In16.Cu" signal "GND7")
		(2 "B.Cu" signal "BOTTOM")
		(9 "F.Adhes" user "F.Adhesive")
		(11 "B.Adhes" user "B.Adhesive")
		(13 "F.Paste" user "Package Geometry/Pastemask Top")
		(15 "B.Paste" user "Package Geometry/Pastemask Bottom")
		(5 "F.SilkS" user "Ref Des/Silkscreen Top")
		(7 "B.SilkS" user "Ref Des/Silkscreen Bottom")
		(1 "F.Mask" user "Board Geometry/Soldermask Top")
		(3 "B.Mask" user "Board Geometry/Soldermask Bottom")
		(17 "Dwgs.User" user "User.Drawings")
		(19 "Cmts.User" user "User.Comments")
		(21 "Eco1.User" user "User.Eco1")
		(23 "Eco2.User" user "User.Eco2")
		(25 "Edge.Cuts" user "Board Geometry/Outline")
		(27 "Margin" user)
		(31 "F.CrtYd" user "Package Geometry/Place Bound Top")
		(29 "B.CrtYd" user "Package Geometry/Place Bound Bottom")
		(35 "F.Fab" user "Ref Des/Assembly Top")
		(33 "B.Fab" user "Ref Des/Assembly Bottom")
	)
	(footprint ""
		(layer "F.Cu")
		(at 125.749812 -440.489848)
		(property "Reference" "J110"
			(at -4.40944 23.347172 0)
			(unlocked yes)
			(layer "F.SilkS")
			(effects
				(font
					(size 0.7874 0.5842)
					(thickness 0.1524)
				)
				(justify left)
			)
		)
		(property "Value" ""
			(at 0 0 0)
			(layer "F.Fab")
			(effects
				(font
					(size 1.27 1.27)
				)
			)
		)
		(duplicate_pad_numbers_are_jumpers no)
		(pad "A1" thru_hole rect
			(at 0 0 180)
			(size 0.766318 0.766318)
			(drill 0.359918)
			(layers "*.Cu" "*.Mask")
			(remove_unused_layers no)
			(net "GPU_FPGA_EROT_RECOV_BUF_N")
			(clearance 0.0508)
			(thermal_gap 0.0508)
			(padstack
				(mode front_inner_back)
				(layer "Inner"
					(shape circle)
					(size 0.766318 0.766318)
					(clearance 0.0508)
				)
				(layer "B.Cu"
					(shape rect)
					(size 0.766318 0.766318)
					(clearance 0.0508)
				)
			)
		)
		(pad "A2" thru_hole circle
			(at 1.999996 0.199898 180)
			(size 0.906272 0.906272)
			(drill 0.499872)
			(layers "*.Cu" "*.Mask")
			(remove_unused_layers no)
			(net "GND")
			(clearance 0.0508)
			(thermal_gap 0.0508)
		)
		(pad "A3" thru_hole circle
			(at 3.999992 0 180)
			(size 0.766318 0.766318)
			(drill 0.359918)
			(layers "*.Cu" "*.Mask")
			(remove_unused_layers no)
			(net "GPU_HMC_PRSNT_N")
			(clearance 0.0508)
			(thermal_gap 0.0508)
		)
		(pad "A4" thru_hole circle
			(at 5.999988 0.199898 180)
			(size 0.906272 0.906272)
			(drill 0.499872)
			(layers "*.Cu" "*.Mask")
			(remove_unused_layers no)
			(net "GND")
			(clearance 0.0508)
			(thermal_gap 0.0508)
		)
		(pad "A5" thru_hole circle
			(at 7.999984 0 180)
			(size 0.766318 0.766318)
			(drill 0.359918)
			(layers "*.Cu" "*.Mask")
			(remove_unused_layers no)
			(net "GPU_BASE_HMC_READY")
			(clearance 0.0508)
			(thermal_gap 0.0508)
		)
		(pad "A6" thru_hole circle
			(at 9.99998 0.199898 180)
			(size 0.906272 0.906272)
			(drill 0.499872)
			(layers "*.Cu" "*.Mask")
			(remove_unused_layers no)
			(net "GND")
			(clearance 0.0508)
			(thermal_gap 0.0508)
		)
		(pad "A7" thru_hole circle
			(at 11.999976 0 180)
			(size 0.766318 0.766318)
			(drill 0.359918)
			(layers "*.Cu" "*.Mask")
			(remove_unused_layers no)
			(net "GPU_BASE_STBY_EN_BUF")
			(clearance 0.0508)
			(thermal_gap 0.0508)
		)
		(pad "A8" thru_hole circle
			(at 13.999972 0.199898 180)
			(size 0.906272 0.906272)
			(drill 0.499872)
			(layers "*.Cu" "*.Mask")
			(remove_unused_layers no)
			(net "GND")
			(clearance 0.0508)
			(thermal_gap 0.0508)
		)
		(pad "B1" thru_hole circle
			(at 0 1.199896 180)
			(size 0.906272 0.906272)
			(drill 0.499872)
			(layers "*.Cu" "*.Mask")
			(remove_unused_layers no)
			(net "GND")
			(clearance 0.0508)
			(thermal_gap 0.0508)
		)
		(pad "B3" thru_hole circle
			(at 3.999992 1.199896 180)
			(size 0.906272 0.906272)
			(drill 0.499872)
			(layers "*.Cu" "*.Mask")
			(remove_unused_layers no)
			(net "GND")
			(clearance 0.0508)
			(thermal_gap 0.0508)
		)
		(pad "B5" thru_hole circle
			(at 7.999984 1.199896 180)
			(size 0.906272 0.906272)
			(drill 0.499872)
			(layers "*.Cu" "*.Mask")
			(remove_unused_layers no)
			(net "GND")
			(clearance 0.0508)
			(thermal_gap 0.0508)
		)
		(pad "B7" thru_hole circle
			(at 11.999976 1.199896 180)
			(size 0.906272 0.906272)
			(drill 0.499872)
			(layers "*.Cu" "*.Mask")
			(remove_unused_layers no)
			(net "GND")
			(clearance 0.0508)
			(thermal_gap 0.0508)
		)
		(pad "D2" thru_hole circle
			(at 1.999996 3.800094 180)
			(size 0.906272 0.906272)
			(drill 0.499872)
			(layers "*.Cu" "*.Mask")
			(remove_unused_layers no)
			(net "GND")
			(clearance 0.0508)
			(thermal_gap 0.0508)
		)
		(pad "D4" thru_hole circle
			(at 5.999988 3.800094 180)
			(size 0.906272 0.906272)
			(drill 0.499872)
			(layers "*.Cu" "*.Mask")
			(remove_unused_layers no)
			(net "GND")
			(clearance 0.0508)
			(thermal_gap 0.0508)
		)
		(pad "D6" thru_hole circle
			(at 9.99998 3.800094 180)
			(size 0.906272 0.906272)
			(drill 0.499872)
			(layers "*.Cu" "*.Mask")
			(remove_unused_layers no)
			(net "GND")
			(clearance 0.0508)
			(thermal_gap 0.0508)
		)
		(pad "D8" thru_hole circle
			(at 13.999972 3.800094 180)
			(size 0.906272 0.906272)
			(drill 0.499872)
			(layers "*.Cu" "*.Mask")
			(remove_unused_layers no)
			(net "GND")
			(clearance 0.0508)
			(thermal_gap 0.0508)
		)
		(pad "E1" thru_hole circle
			(at 0 4.800092 180)
			(size 0.906272 0.906272)
			(drill 0.499872)
			(layers "*.Cu" "*.Mask")
			(remove_unused_layers no)
			(net "GND")
			(clearance 0.0508)
			(thermal_gap 0.0508)
		)
		(pad "E3" thru_hole circle
			(at 3.999992 4.800092 180)
			(size 0.906272 0.906272)
			(drill 0.499872)
			(layers "*.Cu" "*.Mask")
			(remove_unused_layers no)
			(net "GND")
			(clearance 0.0508)
			(thermal_gap 0.0508)
		)
		(pad "E5" thru_hole circle
			(at 7.999984 4.800092 180)
			(size 0.906272 0.906272)
			(drill 0.499872)
			(layers "*.Cu" "*.Mask")
			(remove_unused_layers no)
			(net "GND")
			(clearance 0.0508)
			(thermal_gap 0.0508)
		)
		(pad "E7" thru_hole circle
			(at 11.999976 4.800092 180)
			(size 0.906272 0.906272)
			(drill 0.499872)
			(layers "*.Cu" "*.Mask")
			(remove_unused_layers no)
			(net "GND")
			(clearance 0.0508)
			(thermal_gap 0.0508)
		)
		(pad "G2" thru_hole circle
			(at 1.999996 7.400036 180)
			(size 0.906272 0.906272)
			(drill 0.499872)
			(layers "*.Cu" "*.Mask")
			(remove_unused_layers no)
			(net "GND")
			(clearance 0.0508)
			(thermal_gap 0.0508)
		)
		(pad "G4" thru_hole circle
			(at 5.999988 7.400036 180)
			(size 0.906272 0.906272)
			(drill 0.499872)
			(layers "*.Cu" "*.Mask")
			(remove_unused_layers no)
			(net "GND")
			(clearance 0.0508)
			(thermal_gap 0.0508)
		)
		(pad "G6" thru_hole circle
			(at 9.99998 7.400036 180)
			(size 0.906272 0.906272)
			(drill 0.499872)
			(layers "*.Cu" "*.Mask")
			(remove_unused_layers no)
			(net "GND")
			(clearance 0.0508)
			(thermal_gap 0.0508)
		)
		(pad "G8" thru_hole circle
			(at 13.999972 7.400036 180)
			(size 0.906272 0.906272)
			(drill 0.499872)
			(layers "*.Cu" "*.Mask")
			(remove_unused_layers no)
			(net "GND")
			(clearance 0.0508)
			(thermal_gap 0.0508)
		)
		(pad "H1" thru_hole circle
			(at 0 8.400034 180)
			(size 0.906272 0.906272)
			(drill 0.499872)
			(layers "*.Cu" "*.Mask")
			(remove_unused_layers no)
			(net "GND")
			(clearance 0.0508)
			(thermal_gap 0.0508)
		)
		(pad "H3" thru_hole circle
			(at 3.999992 8.400034 180)
			(size 0.906272 0.906272)
			(drill 0.499872)
			(layers "*.Cu" "*.Mask")
			(remove_unused_layers no)
			(net "GND")
			(clearance 0.0508)
			(thermal_gap 0.0508)
		)
		(pad "H5" thru_hole circle
			(at 7.999984 8.400034 180)
			(size 0.906272 0.906272)
			(drill 0.499872)
			(layers "*.Cu" "*.Mask")
			(remove_unused_layers no)
			(net "GND")
			(clearance 0.0508)
			(thermal_gap 0.0508)
		)
		(pad "H7" thru_hole circle
			(at 11.999976 8.400034 180)
			(size 0.906272 0.906272)
			(drill 0.499872)
			(layers "*.Cu" "*.Mask")
			(remove_unused_layers no)
			(net "GND")
			(clearance 0.0508)
			(thermal_gap 0.0508)
		)
		(pad "J2" thru_hole circle
			(at 1.999996 10.999978 180)
			(size 0.906272 0.906272)
			(drill 0.499872)
			(layers "*.Cu" "*.Mask")
			(remove_unused_layers no)
			(net "GND")
			(clearance 0.0508)
			(thermal_gap 0.0508)
		)
		(pad "J4" thru_hole circle
			(at 5.999988 10.999978 180)
			(size 0.906272 0.906272)
			(drill 0.499872)
			(layers "*.Cu" "*.Mask")
			(remove_unused_layers no)
			(net "GND")
			(clearance 0.0508)
			(thermal_gap 0.0508)
		)
		(pad "J6" thru_hole circle
			(at 9.99998 10.999978 180)
			(size 0.906272 0.906272)
			(drill 0.499872)
			(layers "*.Cu" "*.Mask")
			(remove_unused_layers no)
			(net "GND")
			(clearance 0.0508)
			(thermal_gap 0.0508)
		)
	)
)
